FILE_TYPE=LIBRARY_PARTS;
primitive 'ADC128D818','ADC128D818_SM';
  pin
    'A0':
      PIN_NUMBER='(7)';
      INPUT_LOAD='(-0.01,0.01)';
    'A1':
      PIN_NUMBER='(8)';
      INPUT_LOAD='(-0.01,0.01)';
    'GND':
      PIN_NUMBER='(4)';
      PINUSE='GROUND';
      NO_LOAD_CHECK='Both';
      NO_IO_CHECK='Both';
      NO_ASSERT_CHECK='TRUE';
      NO_DIR_CHECK='TRUE';
      ALLOW_CONNECT='TRUE';
    'IN0':
      PIN_NUMBER='(16)';
      INPUT_LOAD='(-0.01,0.01)';
    'IN1':
      PIN_NUMBER='(15)';
      INPUT_LOAD='(-0.01,0.01)';
    'IN2':
      PIN_NUMBER='(14)';
      INPUT_LOAD='(-0.01,0.01)';
    'IN3':
      PIN_NUMBER='(13)';
      INPUT_LOAD='(-0.01,0.01)';
    'IN4':
      PIN_NUMBER='(12)';
      INPUT_LOAD='(-0.01,0.01)';
    'IN5':
      PIN_NUMBER='(11)';
      INPUT_LOAD='(-0.01,0.01)';
    'IN6':
      PIN_NUMBER='(10)';
      INPUT_LOAD='(-0.01,0.01)';
    'IN7':
      PIN_NUMBER='(9)';
      INPUT_LOAD='(-0.01,0.01)';
    'INT_N':
      PIN_NUMBER='(6)';
      OUTPUT_LOAD='(1.0,-1.0)';
    'SCL':
      PIN_NUMBER='(3)';
      INPUT_LOAD='(-0.01,0.01)';
    'SDA':
      PIN_NUMBER='(2)';
      BIDIRECTIONAL='TRUE';
      INPUT_LOAD='(-0.01,0.01)';
      OUTPUT_LOAD='(1.0,-1.0)';
    'VP':
      PIN_NUMBER='(5)';
      PINUSE='POWER';
      NO_LOAD_CHECK='Both';
      NO_IO_CHECK='Both';
      NO_ASSERT_CHECK='TRUE';
      NO_DIR_CHECK='TRUE';
      ALLOW_CONNECT='TRUE';
    'VREF':
      PIN_NUMBER='(1)';
      INPUT_LOAD='(-0.01,0.01)';
  end_pin;
  body
    PART_NAME='ADC128D818';
    PHYS_DES_PREFIX='U';
  end_body;
end_primitive;

END.
